FILE_TYPE = CONNECTIVITY;
{Allegro Design Entry HDL 17.2-2016 S081 (4005846) 1/11/2022}
"PAGE_NUMBER" = 64;
0"NC";
END.
